# T6G (Grand Teton) — schematic netlist excerpt (pin names and nets, part order shuffled) for the footprints in the layout excerpt that follows; sources: Cadence DE-HDL packaged netlist, KiCad conversion of 04192023_DAF0TMB3IC0_F0TG_MB_C_brd_V02_OCP.brd

H8027  HOLE  EMPTY  pkg TH  page 230 : \1\ = GND
PC207_1  Q_CAP  0.1UF 25V 10% X7R  pkg 0402  page 208 : A = SW_P12V_AUX_PVDD11_S3_P0_FLT ; B = GND
C1509  Q_CAP  0.1UF 16V 10% X7R  pkg C0402  page 172 : A = PVDD18_S5_P0 ; B = GND

(kicad_pcb
	(version 20260206)
	(generator "pcbnew")
	(generator_version "10.0")
	(general
		(thickness 1.6)
		(legacy_teardrops no)
	)
	(paper "A4")
	(title_block
		(title "04192023_DAF0TMB3IC0_F0TG_MB_C_brd_V02_OCP.brd")
		(comment 1 "Grand Teton / footprints 2818-2820 of 8354")
	)
	(layers
		(0 "F.Cu" signal "TOP")
		(4 "In1.Cu" signal "GND")
		(6 "In2.Cu" signal "IN1")
		(8 "In3.Cu" signal "GND1")
		(10 "In4.Cu" signal "IN2")
		(12 "In5.Cu" signal "GND2")
		(14 "In6.Cu" signal "IN3")
		(16 "In7.Cu" signal "GND3")
		(18 "In8.Cu" signal "VCC")
		(20 "In9.Cu" signal "VCC1")
		(22 "In10.Cu" signal "GND4")
		(24 "In11.Cu" signal "IN4")
		(26 "In12.Cu" signal "GND5")
		(28 "In13.Cu" signal "IN5")
		(30 "In14.Cu" signal "GND6")
		(32 "In15.Cu" signal "IN6")
		(34 "In16.Cu" signal "GND7")
		(2 "B.Cu" signal "BOTTOM")
		(9 "F.Adhes" user "F.Adhesive")
		(11 "B.Adhes" user "B.Adhesive")
		(13 "F.Paste" user "Package Geometry/Pastemask Top")
		(15 "B.Paste" user "Package Geometry/Pastemask Bottom")
		(5 "F.SilkS" user "Ref Des/Silkscreen Top")
		(7 "B.SilkS" user "Ref Des/Silkscreen Bottom")
		(1 "F.Mask" user "Board Geometry/Soldermask Top")
		(3 "B.Mask" user "Board Geometry/Soldermask Bottom")
		(17 "Dwgs.User" user "User.Drawings")
		(19 "Cmts.User" user "User.Comments")
		(21 "Eco1.User" user "User.Eco1")
		(23 "Eco2.User" user "User.Eco2")
		(25 "Edge.Cuts" user "Board Geometry/Outline")
		(27 "Margin" user)
		(31 "F.CrtYd" user "Package Geometry/Place Bound Top")
		(29 "B.CrtYd" user "Package Geometry/Place Bound Bottom")
		(35 "F.Fab" user "Ref Des/Assembly Top")
		(33 "B.Fab" user "Ref Des/Assembly Bottom")
	)
	(footprint ""
		(layer "F.Cu")
		(at 427.834552 -355.524562)
		(property "Reference" "PC207_1"
			(at 0 0 0)
			(layer "F.SilkS")
			(hide yes)
			(effects
				(font
					(size 1.27 1.27)
				)
			)
		)
		(property "Value" ""
			(at 0 0 0)
			(layer "F.Fab")
			(effects
				(font
					(size 1.27 1.27)
				)
			)
		)
		(duplicate_pad_numbers_are_jumpers no)
		(fp_line
			(start -0.7874 -0.4064)
			(end 0.7874 -0.4064)
			(stroke
				(width 0.1524)
				(type default)
			)
			(layer "F.SilkS")
		)
		(fp_line
			(start -0.7874 0.4064)
			(end -0.7874 -0.4064)
			(stroke
				(width 0.1524)
				(type default)
			)
			(layer "F.SilkS")
		)
		(fp_line
			(start 0.7874 -0.4064)
			(end 0.7874 0.4064)
			(stroke
				(width 0.1524)
				(type default)
			)
			(layer "F.SilkS")
		)
		(fp_line
			(start 0.7874 0.4064)
			(end -0.7874 0.4064)
			(stroke
				(width 0.1524)
				(type default)
			)
			(layer "F.SilkS")
		)
		(fp_line
			(start -0.67945 -0.305054)
			(end -0.12065 -0.305054)
			(stroke
				(width 0.1)
				(type default)
			)
			(layer "F.Fab")
		)
		(fp_line
			(start -0.67945 0.3048)
			(end -0.67945 -0.305054)
			(stroke
				(width 0.1)
				(type default)
			)
			(layer "F.Fab")
		)
		(fp_line
			(start -0.12065 -0.305054)
			(end -0.12065 -0.2794)
			(stroke
				(width 0.1)
				(type default)
			)
			(layer "F.Fab")
		)
		(fp_line
			(start -0.12065 -0.2794)
			(end 0.12065 -0.2794)
			(stroke
				(width 0.1)
				(type default)
			)
			(layer "F.Fab")
		)
		(fp_line
			(start -0.12065 0.2794)
			(end -0.12065 0.3048)
			(stroke
				(width 0.1)
				(type default)
			)
			(layer "F.Fab")
		)
		(fp_line
			(start -0.12065 0.3048)
			(end -0.67945 0.3048)
			(stroke
				(width 0.1)
				(type default)
			)
			(layer "F.Fab")
		)
		(fp_line
			(start 0.120396 0.2794)
			(end -0.12065 0.2794)
			(stroke
				(width 0.1)
				(type default)
			)
			(layer "F.Fab")
		)
		(fp_line
			(start 0.120396 0.3048)
			(end 0.120396 0.2794)
			(stroke
				(width 0.1)
				(type default)
			)
			(layer "F.Fab")
		)
		(fp_line
			(start 0.12065 -0.3048)
			(end 0.67945 -0.3048)
			(stroke
				(width 0.1)
				(type default)
			)
			(layer "F.Fab")
		)
		(fp_line
			(start 0.12065 -0.2794)
			(end 0.12065 -0.3048)
			(stroke
				(width 0.1)
				(type default)
			)
			(layer "F.Fab")
		)
		(fp_line
			(start 0.67945 -0.3048)
			(end 0.67945 0.3048)
			(stroke
				(width 0.1)
				(type default)
			)
			(layer "F.Fab")
		)
		(fp_line
			(start 0.67945 0.3048)
			(end 0.120396 0.3048)
			(stroke
				(width 0.1)
				(type default)
			)
			(layer "F.Fab")
		)
		(pad "1" smd circle
			(at -0.40005 0)
			(size 0 0)
			(layers "F.Cu" "F.Mask" "F.Paste")
			(net "SW_P12V_AUX_PVDD11_S3_P0_FLT")
		)
		(pad "2" smd circle
			(at 0.40005 0)
			(size 0 0)
			(layers "F.Cu" "F.Mask" "F.Paste")
			(net "GND")
		)
	)
	(footprint ""
		(layer "F.Cu")
		(at 132.885942 -146.856196)
		(property "Reference" "H8027"
			(at -6.168898 4.4323 0)
			(unlocked yes)
			(layer "F.SilkS")
			(effects
				(font
					(size 0.7874 0.5842)
					(thickness 0.1524)
				)
				(justify left)
			)
		)
		(property "Value" ""
			(at 0 0 0)
			(layer "F.Fab")
			(effects
				(font
					(size 1.27 1.27)
				)
			)
		)
		(duplicate_pad_numbers_are_jumpers no)
		(pad "1" thru_hole circle
			(at 0 0)
			(size 6.1976 6.1976)
			(drill 3.7338)
			(layers "*.Cu" "*.Mask")
			(remove_unused_layers no)
			(net "GND")
			(clearance -0.9779)
			(padstack
				(mode front_inner_back)
				(layer "Inner"
					(shape circle)
					(size 5.5372 5.5372)
					(clearance -0.6477)
				)
				(layer "B.Cu"
					(shape circle)
					(size 6.1976 6.1976)
					(clearance -0.9779)
				)
			)
		)
	)
	(footprint ""
		(layer "F.Cu")
		(at 271.607788 -102.247192 90)
		(property "Reference" "C1509"
			(at 0 0 90)
			(layer "F.SilkS")
			(hide yes)
			(effects
				(font
					(size 1.27 1.27)
				)
			)
		)
		(property "Value" ""
			(at 0 0 90)
			(layer "F.Fab")
			(effects
				(font
					(size 1.27 1.27)
				)
			)
		)
		(duplicate_pad_numbers_are_jumpers no)
		(fp_line
			(start 0.7874 -0.4064)
			(end 0.7874 0.4064)
			(stroke
				(width 0.1524)
				(type default)
			)
			(layer "F.SilkS")
		)
		(fp_line
			(start -0.7874 -0.4064)
			(end 0.7874 -0.4064)
			(stroke
				(width 0.1524)
				(type default)
			)
			(layer "F.SilkS")
		)
		(fp_line
			(start 0.7874 0.4064)
			(end -0.7874 0.4064)
			(stroke
				(width 0.1524)
				(type default)
			)
			(layer "F.SilkS")
		)
		(fp_line
			(start -0.7874 0.4064)
			(end -0.7874 -0.4064)
			(stroke
				(width 0.1524)
				(type default)
			)
			(layer "F.SilkS")
		)
		(fp_line
			(start -0.12065 -0.305054)
			(end -0.12065 -0.2794)
			(stroke
				(width 0.1)
				(type default)
			)
			(layer "F.Fab")
		)
		(fp_line
			(start -0.67945 -0.305054)
			(end -0.12065 -0.305054)
			(stroke
				(width 0.1)
				(type default)
			)
			(layer "F.Fab")
		)
		(fp_line
			(start 0.67945 -0.3048)
			(end 0.67945 0.3048)
			(stroke
				(width 0.1)
				(type default)
			)
			(layer "F.Fab")
		)
		(fp_line
			(start 0.12065 -0.3048)
			(end 0.67945 -0.3048)
			(stroke
				(width 0.1)
				(type default)
			)
			(layer "F.Fab")
		)
		(fp_line
			(start 0.12065 -0.2794)
			(end 0.12065 -0.3048)
			(stroke
				(width 0.1)
				(type default)
			)
			(layer "F.Fab")
		)
		(fp_line
			(start -0.12065 -0.2794)
			(end 0.12065 -0.2794)
			(stroke
				(width 0.1)
				(type default)
			)
			(layer "F.Fab")
		)
		(fp_line
			(start 0.120396 0.2794)
			(end -0.12065 0.2794)
			(stroke
				(width 0.1)
				(type default)
			)
			(layer "F.Fab")
		)
		(fp_line
			(start -0.12065 0.2794)
			(end -0.12065 0.3048)
			(stroke
				(width 0.1)
				(type default)
			)
			(layer "F.Fab")
		)
		(fp_line
			(start 0.67945 0.3048)
			(end 0.120396 0.3048)
			(stroke
				(width 0.1)
				(type default)
			)
			(layer "F.Fab")
		)
		(fp_line
			(start 0.120396 0.3048)
			(end 0.120396 0.2794)
			(stroke
				(width 0.1)
				(type default)
			)
			(layer "F.Fab")
		)
		(fp_line
			(start -0.12065 0.3048)
			(end -0.67945 0.3048)
			(stroke
				(width 0.1)
				(type default)
			)
			(layer "F.Fab")
		)
		(fp_line
			(start -0.67945 0.3048)
			(end -0.67945 -0.305054)
			(stroke
				(width 0.1)
				(type default)
			)
			(layer "F.Fab")
		)
		(pad "1" smd circle
			(at -0.40005 0 90)
			(size 0 0)
			(layers "F.Cu" "F.Mask" "F.Paste")
			(net "PVDD18_S5_P0")
		)
		(pad "2" smd circle
			(at 0.40005 0 90)
			(size 0 0)
			(layers "F.Cu" "F.Mask" "F.Paste")
			(net "GND")
		)
	)
)
